(kicad_pcb
	(version 20260206)
	(generator "pcbnew")
	(generator_version "10.0")
	(general
		(thickness 1.6)
		(legacy_teardrops no)
	)
	(paper "A4")
	(title_block
		(title "Bryce Canyon_R.DPB_16317-1_OCP.brd")
		(comment 1 "Bryce Canyon / footprints 1888-1892 of 2099")
	)
	(layers
		(0 "F.Cu" signal "TOP")
		(4 "In1.Cu" signal "L2GND")
		(6 "In2.Cu" signal "L3")
		(8 "In3.Cu" signal "L4VCC")
		(10 "In4.Cu" signal "L5VCC")
		(12 "In5.Cu" signal "L6")
		(14 "In6.Cu" signal "L7GND")
		(2 "B.Cu" signal "BOTTOM")
		(9 "F.Adhes" user "F.Adhesive")
		(11 "B.Adhes" user "B.Adhesive")
		(13 "F.Paste" user "Package Geometry/Pastemask Top")
		(15 "B.Paste" user "Package Geometry/Pastemask Bottom")
		(5 "F.SilkS" user "Ref Des/Silkscreen Top")
		(7 "B.SilkS" user "Ref Des/Silkscreen Bottom")
		(1 "F.Mask" user "Board Geometry/Soldermask Top")
		(3 "B.Mask" user "Board Geometry/Soldermask Bottom")
		(17 "Dwgs.User" user "User.Drawings")
		(19 "Cmts.User" user "User.Comments")
		(21 "Eco1.User" user "User.Eco1")
		(23 "Eco2.User" user "User.Eco2")
		(25 "Edge.Cuts" user "Board Geometry/Outline")
		(27 "Margin" user)
		(31 "F.CrtYd" user "Package Geometry/Place Bound Top")
		(29 "B.CrtYd" user "Package Geometry/Place Bound Bottom")
		(35 "F.Fab" user "Ref Des/Assembly Top")
		(33 "B.Fab" user "Ref Des/Assembly Bottom")
	)
	(footprint ""
		(layer "F.Cu")
		(at 426.974 -266.827 180)
		(property "Reference" "C148"
			(at 0 0 180)
			(layer "F.SilkS")
			(hide yes)
			(effects
				(font
					(size 1.27 1.27)
				)
			)
		)
		(property "Value" "SC10U16V6KX-2GP"
			(at -0.0762 -5.1308 180)
			(unlocked yes)
			(layer "F.Fab")
			(hide yes)
			(effects
				(font
					(size 1.016 1.016)
					(thickness 0.1524)
				)
			)
		)
		(property "Device Type" "C1206H71"
			(at -0.127 -6.6548 180)
			(unlocked yes)
			(layer "F.Fab")
			(hide yes)
			(effects
				(font
					(size 1.016 1.016)
					(thickness 0.1524)
				)
			)
		)
		(duplicate_pad_numbers_are_jumpers no)
		(fp_line
			(start 1.016 2.2352)
			(end -1.016 2.2352)
			(stroke
				(width 0.1524)
				(type default)
			)
			(layer "F.SilkS")
		)
		(fp_line
			(start 1.016 0.8382)
			(end 1.016 2.2352)
			(stroke
				(width 0.1524)
				(type default)
			)
			(layer "F.SilkS")
		)
		(fp_line
			(start 1.016 -2.2352)
			(end 1.016 -0.8382)
			(stroke
				(width 0.1524)
				(type default)
			)
			(layer "F.SilkS")
		)
		(fp_line
			(start -1.016 2.2352)
			(end -1.016 0.8382)
			(stroke
				(width 0.1524)
				(type default)
			)
			(layer "F.SilkS")
		)
		(fp_line
			(start -1.016 -0.8382)
			(end -1.016 -2.2352)
			(stroke
				(width 0.1524)
				(type default)
			)
			(layer "F.SilkS")
		)
		(fp_line
			(start -1.016 -2.2352)
			(end 1.016 -2.2352)
			(stroke
				(width 0.1524)
				(type default)
			)
			(layer "F.SilkS")
		)
		(fp_rect
			(start -1.0922 2.3114)
			(end 1.0922 -2.3114)
			(stroke
				(width 0)
				(type default)
			)
			(fill no)
			(layer "F.CrtYd")
		)
		(fp_poly
			(pts
				(xy 1.0922 -2.3114) (xy 1.0922 2.3114) (xy -1.0922 2.3114) (xy -1.0922 -2.3114)
			)
			(stroke
				(width 0)
				(type default)
			)
			(fill no)
			(layer "F.Fab")
		)
		(pad "1" smd rect
			(at 0 -1.397 180)
			(size 1.651 1.27)
			(layers "F.Cu" "F.Mask" "F.Paste")
			(net "P5V_HDD9")
		)
		(pad "2" smd rect
			(at 0 1.397 180)
			(size 1.651 1.27)
			(layers "F.Cu" "F.Mask" "F.Paste")
			(net "GND")
		)
	)
	(footprint ""
		(layer "F.Cu")
		(at 285.651448 -352.748342 180)
		(property "Reference" "U29"
			(at 0 0 180)
			(layer "F.SilkS")
			(hide yes)
			(effects
				(font
					(size 1.27 1.27)
				)
			)
		)
		(property "Value" "MAX31790ATI-T-GP"
			(at 4.1021 -3.7338 180)
			(unlocked yes)
			(layer "F.Fab")
			(hide yes)
			(effects
				(font
					(size 1.016 1.016)
					(thickness 0.1524)
				)
			)
		)
		(property "Device Type" "QFN28-G2D7H32"
			(at 4.1021 -5.2578 180)
			(unlocked yes)
			(layer "F.Fab")
			(hide yes)
			(effects
				(font
					(size 1.016 1.016)
					(thickness 0.1524)
				)
			)
		)
		(duplicate_pad_numbers_are_jumpers no)
		(fp_line
			(start 3.0099 3.0099)
			(end 3.0099 1.7399)
			(stroke
				(width 0.1524)
				(type default)
			)
			(layer "F.SilkS")
		)
		(fp_line
			(start 2.7813 0)
			(end 3.2893 0)
			(stroke
				(width 0.1524)
				(type default)
			)
			(layer "F.SilkS")
		)
		(fp_line
			(start 1.7399 3.0099)
			(end 3.0099 3.0099)
			(stroke
				(width 0.1524)
				(type default)
			)
			(layer "F.SilkS")
		)
		(fp_line
			(start 0.8128 2.7813)
			(end 0.8128 3.5433)
			(stroke
				(width 0.1524)
				(type default)
			)
			(layer "F.SilkS")
		)
		(fp_line
			(start -0.4064 -2.7813)
			(end -0.4064 -3.2893)
			(stroke
				(width 0.1524)
				(type default)
			)
			(layer "F.SilkS")
		)
		(fp_line
			(start -1.1938 2.7813)
			(end -1.1938 3.2893)
			(stroke
				(width 0.1524)
				(type default)
			)
			(layer "F.SilkS")
		)
		(fp_line
			(start -2.7813 -0.4064)
			(end -3.5433 -0.4064)
			(stroke
				(width 0.1524)
				(type default)
			)
			(layer "F.SilkS")
		)
		(fp_line
			(start -3.0099 3.0099)
			(end -1.7399 3.0099)
			(stroke
				(width 0.1524)
				(type default)
			)
			(layer "F.SilkS")
		)
		(fp_line
			(start -3.0099 1.7399)
			(end -3.0099 3.0099)
			(stroke
				(width 0.1524)
				(type default)
			)
			(layer "F.SilkS")
		)
		(fp_line
			(start -3.0099 -1.7399)
			(end -3.0099 -3.0099)
			(stroke
				(width 0.1524)
				(type default)
			)
			(layer "F.SilkS")
		)
		(fp_line
			(start -3.0099 -3.0099)
			(end -1.7399 -3.0099)
			(stroke
				(width 0.1524)
				(type default)
			)
			(layer "F.SilkS")
		)
		(fp_poly
			(pts
				(xy 3.0099 -1.7399) (xy 1.7399 -3.0099) (xy 3.0099 -3.0099)
			)
			(stroke
				(width 0)
				(type default)
			)
			(fill yes)
			(layer "F.SilkS")
		)
		(fp_rect
			(start -1.9939 1.9939)
			(end 1.9939 -1.9939)
			(stroke
				(width 0)
				(type default)
			)
			(fill no)
			(layer "F.CrtYd")
		)
		(fp_poly
			(pts
				(xy -3.0099 3.0099) (xy -3.0099 -3.0099) (xy 3.0099 -3.0099) (xy 3.0099 3.0099) (xy -1.98882 3.0099)
				(xy -1.98882 1.9939) (xy 1.9939 1.9939) (xy 1.9939 -1.9939) (xy -1.9939 -1.9939) (xy -1.9939 3.0099)
			)
			(stroke
				(width 0)
				(type default)
			)
			(fill no)
			(layer "F.CrtYd")
		)
		(fp_rect
			(start -3.0099 3.0099)
			(end 3.0099 -3.0099)
			(stroke
				(width 0)
				(type default)
			)
			(fill no)
			(layer "F.Fab")
		)
		(pad "1" smd rect
			(at 1.199896 -2.032 180)
			(size 0.2032 0.9398)
			(layers "F.Cu" "F.Mask" "F.Paste")
			(net "MAX31790_B_FREQ_ST")
		)
		(pad "2" smd rect
			(at 0.8001 -2.032 180)
			(size 0.2032 0.9398)
			(layers "F.Cu" "F.Mask" "F.Paste")
			(net "MAX31790_B_SPIN_ST")
		)
		(pad "3" smd rect
			(at 0.40005 -2.032 180)
			(size 0.2032 0.9398)
			(layers "F.Cu" "F.Mask" "F.Paste")
			(net "MAX31790_B_ADD1")
		)
		(pad "4" smd rect
			(at 0 -2.032 180)
			(size 0.2032 0.9398)
			(layers "F.Cu" "F.Mask" "F.Paste")
			(net "MAX31790_B_ADD0")
		)
		(pad "5" smd rect
			(at -0.40005 -2.032 180)
			(size 0.2032 0.9398)
			(layers "F.Cu" "F.Mask" "F.Paste")
			(net "MAX31790_B_WD_ST")
		)
		(pad "6" smd rect
			(at -0.8001 -2.032 180)
			(size 0.2032 0.9398)
			(layers "F.Cu" "F.Mask" "F.Paste")
			(net "Net_317")
		)
		(pad "7" smd rect
			(at -1.199896 -2.032 180)
			(size 0.2032 0.9398)
			(layers "F.Cu" "F.Mask" "F.Paste")
			(net "GND")
		)
		(pad "8" smd rect
			(at -2.032 -1.199896 180)
			(size 0.9398 0.2032)
			(layers "F.Cu" "F.Mask" "F.Paste")
			(net "GND")
		)
		(pad "9" smd rect
			(at -2.032 -0.8001 180)
			(size 0.9398 0.2032)
			(layers "F.Cu" "F.Mask" "F.Paste")
			(net "FANTACH_B_R3")
		)
		(pad "10" smd rect
			(at -2.032 -0.40005 180)
			(size 0.9398 0.2032)
			(layers "F.Cu" "F.Mask" "F.Paste")
			(net "Net_320")
		)
		(pad "11" smd rect
			(at -2.032 0 180)
			(size 0.9398 0.2032)
			(layers "F.Cu" "F.Mask" "F.Paste")
			(net "FANTACH_B_F3")
		)
		(pad "12" smd rect
			(at -2.032 0.40005 180)
			(size 0.9398 0.2032)
			(layers "F.Cu" "F.Mask" "F.Paste")
			(net "Net_321")
		)
		(pad "13" smd rect
			(at -2.032 0.8001 180)
			(size 0.9398 0.2032)
			(layers "F.Cu" "F.Mask" "F.Paste")
			(net "FANTACH_B_R2")
		)
		(pad "14" smd rect
			(at -2.032 1.199896 180)
			(size 0.9398 0.2032)
			(layers "F.Cu" "F.Mask" "F.Paste")
			(net "Net_322")
		)
		(pad "15" smd rect
			(at -1.199896 2.032 180)
			(size 0.2032 0.9398)
			(layers "F.Cu" "F.Mask" "F.Paste")
			(net "FANTACH_B_F2")
		)
		(pad "16" smd rect
			(at -0.8001 2.032 180)
			(size 0.2032 0.9398)
			(layers "F.Cu" "F.Mask" "F.Paste")
			(net "Net_319")
		)
		(pad "17" smd rect
			(at -0.40005 2.032 180)
			(size 0.2032 0.9398)
			(layers "F.Cu" "F.Mask" "F.Paste")
			(net "FANTACH_B_R1")
		)
		(pad "18" smd rect
			(at 0 2.032 180)
			(size 0.2032 0.9398)
			(layers "F.Cu" "F.Mask" "F.Paste")
			(net "FANTACH_B_R0")
		)
		(pad "19" smd rect
			(at 0.40005 2.032 180)
			(size 0.2032 0.9398)
			(layers "F.Cu" "F.Mask" "F.Paste")
			(net "FANTACH_B_F1")
		)
		(pad "20" smd rect
			(at 0.8001 2.032 180)
			(size 0.2032 0.9398)
			(layers "F.Cu" "F.Mask" "F.Paste")
			(net "FANTACH_B_F0")
		)
		(pad "21" smd rect
			(at 1.199896 2.032 180)
			(size 0.2032 0.9398)
			(layers "F.Cu" "F.Mask" "F.Paste")
			(net "P3V3_STBY_B")
		)
		(pad "22" smd rect
			(at 2.032 1.199896 180)
			(size 0.9398 0.2032)
			(layers "F.Cu" "F.Mask" "F.Paste")
			(net "MAX31790_B_SDA")
		)
		(pad "23" smd rect
			(at 2.032 0.8001 180)
			(size 0.9398 0.2032)
			(layers "F.Cu" "F.Mask" "F.Paste")
			(net "MAX31790_B_SCL")
		)
		(pad "24" smd rect
			(at 2.032 0.40005 180)
			(size 0.9398 0.2032)
			(layers "F.Cu" "F.Mask" "F.Paste")
			(net "MAX31790_B_FAIL")
		)
		(pad "25" smd rect
			(at 2.032 0 180)
			(size 0.9398 0.2032)
			(layers "F.Cu" "F.Mask" "F.Paste")
			(net "MAX31790_B_PWM_ST0")
		)
		(pad "26" smd rect
			(at 2.032 -0.40005 180)
			(size 0.9398 0.2032)
			(layers "F.Cu" "F.Mask" "F.Paste")
			(net "MAX31790_B_PWM_ST1")
		)
		(pad "27" smd rect
			(at 2.032 -0.8001 180)
			(size 0.9398 0.2032)
			(layers "F.Cu" "F.Mask" "F.Paste")
			(net "MAX31790_B_FULL_SPEED")
		)
		(pad "28" smd rect
			(at 2.032 -1.199896 180)
			(size 0.9398 0.2032)
			(layers "F.Cu" "F.Mask" "F.Paste")
			(net "Net_318")
		)
		(pad "29" smd rect
			(at 0 0 180)
			(size 2.6924 2.6924)
			(layers "F.Cu" "F.Mask" "F.Paste")
			(net "GND")
		)
	)
	(footprint ""
		(layer "F.Cu")
		(at 331.47 -262.001 -90)
		(property "Reference" "R254"
			(at 0 0 270)
			(layer "F.SilkS")
			(hide yes)
			(effects
				(font
					(size 1.27 1.27)
				)
			)
		)
		(property "Value" "2R6F-GP"
			(at -0.0508 -4.8514 270)
			(unlocked yes)
			(layer "F.Fab")
			(hide yes)
			(effects
				(font
					(size 1.016 1.016)
					(thickness 0.1524)
				)
			)
		)
		(property "Device Type" "R1206H26"
			(at 0 -6.3754 270)
			(unlocked yes)
			(layer "F.Fab")
			(hide yes)
			(effects
				(font
					(size 1.016 1.016)
					(thickness 0.1524)
				)
			)
		)
		(duplicate_pad_numbers_are_jumpers no)
		(fp_line
			(start -1.016 2.2352)
			(end -1.016 -2.2352)
			(stroke
				(width 0.1524)
				(type default)
			)
			(layer "F.SilkS")
		)
		(fp_line
			(start 1.016 2.2352)
			(end -1.016 2.2352)
			(stroke
				(width 0.1524)
				(type default)
			)
			(layer "F.SilkS")
		)
		(fp_line
			(start -1.016 -2.2352)
			(end 1.016 -2.2352)
			(stroke
				(width 0.1524)
				(type default)
			)
			(layer "F.SilkS")
		)
		(fp_line
			(start 1.016 -2.2352)
			(end 1.016 2.2352)
			(stroke
				(width 0.1524)
				(type default)
			)
			(layer "F.SilkS")
		)
		(fp_rect
			(start -1.0922 2.3114)
			(end 1.0922 -2.3114)
			(stroke
				(width 0)
				(type default)
			)
			(fill no)
			(layer "F.CrtYd")
		)
		(fp_poly
			(pts
				(xy -1.0922 -2.3114) (xy 1.0922 -2.3114) (xy 1.0922 2.3114) (xy -1.0922 2.3114)
			)
			(stroke
				(width 0)
				(type default)
			)
			(fill no)
			(layer "F.Fab")
		)
		(pad "1" smd rect
			(at 0 -1.397 270)
			(size 1.651 1.27)
			(layers "F.Cu" "F.Mask" "F.Paste")
			(net "P5V_HDD6")
		)
		(pad "2" smd rect
			(at 0 1.397 270)
			(size 1.651 1.27)
			(layers "F.Cu" "F.Mask" "F.Paste")
			(net "5V_PRE_6")
		)
	)
	(footprint ""
		(layer "F.Cu")
		(at 398.145 -10.16 180)
		(property "Reference" "R816"
			(at 0 0 180)
			(layer "F.SilkS")
			(hide yes)
			(effects
				(font
					(size 1.27 1.27)
				)
			)
		)
		(property "Value" "0R2J-2-GP"
			(at 0.064008 -3.993896 180)
			(unlocked yes)
			(layer "F.Fab")
			(hide yes)
			(effects
				(font
					(size 1.016 1.016)
					(thickness 0.1524)
				)
			)
		)
		(property "Device Type" "R402H16"
			(at 0.064008 -5.517896 180)
			(unlocked yes)
			(layer "F.Fab")
			(hide yes)
			(effects
				(font
					(size 1.016 1.016)
					(thickness 0.1524)
				)
			)
		)
		(duplicate_pad_numbers_are_jumpers no)
		(fp_line
			(start 0.508 -0.9398)
			(end -0.508 -0.9398)
			(stroke
				(width 0.1524)
				(type default)
			)
			(layer "F.SilkS")
		)
		(fp_line
			(start -0.508 -0.9398)
			(end -0.508 0.9398)
			(stroke
				(width 0.1524)
				(type default)
			)
			(layer "F.SilkS")
		)
		(fp_rect
			(start -0.508 0.9398)
			(end 0.508 -0.9398)
			(stroke
				(width 0)
				(type default)
			)
			(fill no)
			(layer "F.CrtYd")
		)
		(fp_rect
			(start -0.508 0.9398)
			(end 0.508 -0.9398)
			(stroke
				(width 0)
				(type default)
			)
			(fill no)
			(layer "F.Fab")
		)
		(pad "1" smd custom
			(at 0 -0.4445 180)
			(size 0.1397 0.1397)
			(layers "F.Cu" "F.Mask" "F.Paste")
			(net "DRIVE_B_32_PWR")
			(options
				(clearance outline)
				(anchor circle)
			)
			(primitives
				(gr_poly
					(pts
						(arc
							(start -0.1778 -0.2794)
							(mid -0.249642 -0.249642)
							(end -0.2794 -0.1778)
						)
						(arc
							(start -0.2794 0.1778)
							(mid -0.249642 0.249642)
							(end -0.1778 0.2794)
						)
						(arc
							(start 0.1778 0.2794)
							(mid 0.249642 0.249642)
							(end 0.2794 0.1778)
						)
						(arc
							(start 0.2794 -0.1778)
							(mid 0.249642 -0.249642)
							(end 0.1778 -0.2794)
						)
					)
					(width 0)
					(fill yes)
				)
			)
		)
		(pad "2" smd custom
			(at 0 0.4445 180)
			(size 0.1397 0.1397)
			(layers "F.Cu" "F.Mask" "F.Paste")
			(net "SW_PWR_R_HDD32")
			(options
				(clearance outline)
				(anchor circle)
			)
			(primitives
				(gr_poly
					(pts
						(arc
							(start -0.1778 -0.2794)
							(mid -0.249642 -0.249642)
							(end -0.2794 -0.1778)
						)
						(arc
							(start -0.2794 0.1778)
							(mid -0.249642 0.249642)
							(end -0.1778 0.2794)
						)
						(arc
							(start 0.1778 0.2794)
							(mid 0.249642 0.249642)
							(end 0.2794 0.1778)
						)
						(arc
							(start 0.2794 -0.1778)
							(mid 0.249642 -0.249642)
							(end 0.1778 -0.2794)
						)
					)
					(width 0)
					(fill yes)
				)
			)
		)
	)
	(footprint ""
		(layer "F.Cu")
		(at 260.462522 -369.798346 90)
		(property "Reference" "R1027"
			(at 0 0 90)
			(layer "F.SilkS")
			(hide yes)
			(effects
				(font
					(size 1.27 1.27)
				)
			)
		)
		(property "Value" "0R2J-2-GP"
			(at 0.064008 -3.993896 90)
			(unlocked yes)
			(layer "F.Fab")
			(hide yes)
			(effects
				(font
					(size 1.016 1.016)
					(thickness 0.1524)
				)
			)
		)
		(property "Device Type" "R402H16"
			(at 0.064008 -5.517896 90)
			(unlocked yes)
			(layer "F.Fab")
			(hide yes)
			(effects
				(font
					(size 1.016 1.016)
					(thickness 0.1524)
				)
			)
		)
		(duplicate_pad_numbers_are_jumpers no)
		(fp_line
			(start 0.508 -0.9398)
			(end -0.508 -0.9398)
			(stroke
				(width 0.1524)
				(type default)
			)
			(layer "F.SilkS")
		)
		(fp_line
			(start -0.508 -0.9398)
			(end -0.508 0.9398)
			(stroke
				(width 0.1524)
				(type default)
			)
			(layer "F.SilkS")
		)
		(fp_rect
			(start -0.508 0.9398)
			(end 0.508 -0.9398)
			(stroke
				(width 0)
				(type default)
			)
			(fill no)
			(layer "F.CrtYd")
		)
		(fp_rect
			(start -0.508 0.9398)
			(end 0.508 -0.9398)
			(stroke
				(width 0)
				(type default)
			)
			(fill no)
			(layer "F.Fab")
		)
		(pad "1" smd custom
			(at 0 -0.4445 90)
			(size 0.1397 0.1397)
			(layers "F.Cu" "F.Mask" "F.Paste")
			(net "MB3_SCL_R")
			(options
				(clearance outline)
				(anchor circle)
			)
			(primitives
				(gr_poly
					(pts
						(arc
							(start -0.1778 -0.2794)
							(mid -0.249642 -0.249642)
							(end -0.2794 -0.1778)
						)
						(arc
							(start -0.2794 0.1778)
							(mid -0.249642 0.249642)
							(end -0.1778 0.2794)
						)
						(arc
							(start 0.1778 0.2794)
							(mid 0.249642 0.249642)
							(end 0.2794 0.1778)
						)
						(arc
							(start 0.2794 -0.1778)
							(mid 0.249642 -0.249642)
							(end 0.1778 -0.2794)
						)
					)
					(width 0)
					(fill yes)
				)
			)
		)
		(pad "2" smd custom
			(at 0 0.4445 90)
			(size 0.1397 0.1397)
			(layers "F.Cu" "F.Mask" "F.Paste")
			(net "I2C_DPB_B_SCL_BUF")
			(options
				(clearance outline)
				(anchor circle)
			)
			(primitives
				(gr_poly
					(pts
						(arc
							(start -0.1778 -0.2794)
							(mid -0.249642 -0.249642)
							(end -0.2794 -0.1778)
						)
						(arc
							(start -0.2794 0.1778)
							(mid -0.249642 0.249642)
							(end -0.1778 0.2794)
						)
						(arc
							(start 0.1778 0.2794)
							(mid 0.249642 0.249642)
							(end 0.2794 0.1778)
						)
						(arc
							(start 0.2794 -0.1778)
							(mid 0.249642 -0.249642)
							(end 0.1778 -0.2794)
						)
					)
					(width 0)
					(fill yes)
				)
			)
		)
	)
)
